(kicad_pcb
	(version 20260206)
	(generator "pcbnew")
	(generator_version "10.0")
	(general
		(thickness 1.6)
		(legacy_teardrops no)
	)
	(paper "A4")
	(title_block
		(title "01162023_DA0F0TEBIF0_F0T_Expander_BD_F_brd_V02_OCP.brd")
		(comment 1 "Grand Teton / footprints 2893-2897 of 9728")
	)
	(layers
		(0 "F.Cu" signal "TOP")
		(4 "In1.Cu" signal "GND")
		(6 "In2.Cu" signal "VCC")
		(8 "In3.Cu" signal "VCC1")
		(10 "In4.Cu" signal "GND1")
		(12 "In5.Cu" signal "IN1")
		(14 "In6.Cu" signal "GND2")
		(16 "In7.Cu" signal "IN2")
		(18 "In8.Cu" signal "GND3")
		(20 "In9.Cu" signal "IN3")
		(22 "In10.Cu" signal "GND4")
		(24 "In11.Cu" signal "IN4")
		(26 "In12.Cu" signal "GND5")
		(28 "In13.Cu" signal "IN5")
		(30 "In14.Cu" signal "GND6")
		(32 "In15.Cu" signal "IN6")
		(34 "In16.Cu" signal "GND7")
		(2 "B.Cu" signal "BOTTOM")
		(9 "F.Adhes" user "F.Adhesive")
		(11 "B.Adhes" user "B.Adhesive")
		(13 "F.Paste" user "Package Geometry/Pastemask Top")
		(15 "B.Paste" user "Package Geometry/Pastemask Bottom")
		(5 "F.SilkS" user "Ref Des/Silkscreen Top")
		(7 "B.SilkS" user "Ref Des/Silkscreen Bottom")
		(1 "F.Mask" user "Board Geometry/Soldermask Top")
		(3 "B.Mask" user "Board Geometry/Soldermask Bottom")
		(17 "Dwgs.User" user "User.Drawings")
		(19 "Cmts.User" user "User.Comments")
		(21 "Eco1.User" user "User.Eco1")
		(23 "Eco2.User" user "User.Eco2")
		(25 "Edge.Cuts" user "Board Geometry/Outline")
		(27 "Margin" user)
		(31 "F.CrtYd" user "Package Geometry/Place Bound Top")
		(29 "B.CrtYd" user "Package Geometry/Place Bound Bottom")
		(35 "F.Fab" user "Ref Des/Assembly Top")
		(33 "B.Fab" user "Ref Des/Assembly Bottom")
	)
	(footprint ""
		(layer "F.Cu")
		(at 325.401178 -55.78475 -90)
		(property "Reference" "PD115"
			(at 3.86715 2.108708 90)
			(unlocked yes)
			(layer "F.SilkS")
			(effects
				(font
					(size 0.7874 0.5842)
					(thickness 0.1524)
				)
				(justify left)
			)
		)
		(property "Value" ""
			(at 0 0 270)
			(layer "F.Fab")
			(effects
				(font
					(size 1.27 1.27)
				)
			)
		)
		(duplicate_pad_numbers_are_jumpers no)
		(fp_line
			(start -3.400044 1.459992)
			(end -3.400044 -1.459992)
			(stroke
				(width 0.1524)
				(type default)
			)
			(layer "F.SilkS")
		)
		(fp_line
			(start 4.107942 1.459992)
			(end -3.400044 1.459992)
			(stroke
				(width 0.1524)
				(type default)
			)
			(layer "F.SilkS")
		)
		(fp_line
			(start -3.400044 -1.459992)
			(end 4.107942 -1.459992)
			(stroke
				(width 0.1524)
				(type default)
			)
			(layer "F.SilkS")
		)
		(fp_line
			(start 4.107942 -1.459992)
			(end 4.107942 1.459992)
			(stroke
				(width 0.1524)
				(type default)
			)
			(layer "F.SilkS")
		)
		(fp_poly
			(pts
				(xy 4.107942 -1.459992) (xy 4.107942 1.459992) (xy 3.308096 1.459992) (xy 3.308096 -1.459992)
			)
			(stroke
				(width 0)
				(type default)
			)
			(fill yes)
			(layer "F.SilkS")
		)
		(fp_line
			(start -2.29997 1.459992)
			(end -2.29997 -1.459992)
			(stroke
				(width 0.1)
				(type default)
			)
			(layer "F.Fab")
		)
		(fp_line
			(start 2.29997 1.459992)
			(end -2.29997 1.459992)
			(stroke
				(width 0.1)
				(type default)
			)
			(layer "F.Fab")
		)
		(fp_line
			(start -2.29997 -1.459992)
			(end 2.29997 -1.459992)
			(stroke
				(width 0.1)
				(type default)
			)
			(layer "F.Fab")
		)
		(fp_line
			(start 2.29997 -1.459992)
			(end 2.29997 1.459992)
			(stroke
				(width 0.1)
				(type default)
			)
			(layer "F.Fab")
		)
		(fp_text user "-"
			(at 5.4102 0.29845 90)
			(unlocked yes)
			(layer "F.SilkS")
			(effects
				(font
					(size 1.905 1.4224)
					(thickness 0.1524)
				)
				(justify left)
			)
		)
		(fp_text user "+"
			(at -4.7752 -0.12065 270)
			(unlocked yes)
			(layer "F.SilkS")
			(effects
				(font
					(size 1.905 1.4224)
					(thickness 0.1524)
				)
				(justify left)
			)
		)
		(fp_text user "-"
			(at 5.4102 0.29845 90)
			(unlocked yes)
			(layer "F.Fab")
			(effects
				(font
					(size 1.905 1.4224)
					(thickness 0.1524)
				)
				(justify left)
			)
		)
		(fp_text user "+"
			(at -4.7752 -0.12065 270)
			(unlocked yes)
			(layer "F.Fab")
			(effects
				(font
					(size 1.905 1.4224)
					(thickness 0.1524)
				)
				(justify left)
			)
		)
		(pad "A" smd rect
			(at -1.999996 0)
			(size 1.7018 2.5146)
			(layers "F.Cu" "F.Mask" "F.Paste")
			(net "GND")
		)
		(pad "C" smd rect
			(at 1.999996 0)
			(size 1.7018 2.5146)
			(layers "F.Cu" "F.Mask" "F.Paste")
			(net "P12V_SSD11_R")
		)
	)
	(footprint ""
		(layer "F.Cu")
		(at 371.14607 -46.4439 180)
		(property "Reference" "U75"
			(at 0.40767 -2.45237 0)
			(unlocked yes)
			(layer "F.SilkS")
			(effects
				(font
					(size 0.7874 0.5842)
					(thickness 0.1524)
				)
			)
		)
		(property "Value" ""
			(at 0 0 180)
			(layer "F.Fab")
			(effects
				(font
					(size 1.27 1.27)
				)
			)
		)
		(duplicate_pad_numbers_are_jumpers no)
		(fp_line
			(start 1.500124 1.500124)
			(end 1.004062 1.500124)
			(stroke
				(width 0.1524)
				(type default)
			)
			(layer "F.SilkS")
		)
		(fp_line
			(start 1.500124 1.004062)
			(end 1.500124 1.500124)
			(stroke
				(width 0.1524)
				(type default)
			)
			(layer "F.SilkS")
		)
		(fp_line
			(start 1.500124 -1.500124)
			(end 1.500124 -1.004062)
			(stroke
				(width 0.1524)
				(type default)
			)
			(layer "F.SilkS")
		)
		(fp_line
			(start 1.004062 -1.500124)
			(end 1.500124 -1.500124)
			(stroke
				(width 0.1524)
				(type default)
			)
			(layer "F.SilkS")
		)
		(fp_line
			(start -1.004062 1.500124)
			(end -1.500124 1.500124)
			(stroke
				(width 0.1524)
				(type default)
			)
			(layer "F.SilkS")
		)
		(fp_line
			(start -1.500124 1.500124)
			(end -1.500124 1.004062)
			(stroke
				(width 0.1524)
				(type default)
			)
			(layer "F.SilkS")
		)
		(fp_line
			(start -1.500124 -1.004062)
			(end -1.500124 -1.500124)
			(stroke
				(width 0.1524)
				(type default)
			)
			(layer "F.SilkS")
		)
		(fp_line
			(start -1.500124 -1.500124)
			(end -1.004062 -1.500124)
			(stroke
				(width 0.1524)
				(type default)
			)
			(layer "F.SilkS")
		)
		(fp_poly
			(pts
				(xy -1.957578 -2.17932) (xy -2.67589 -1.461008) (xy -1.598422 -1.101598)
			)
			(stroke
				(width 0)
				(type default)
			)
			(fill yes)
			(layer "F.SilkS")
		)
		(fp_line
			(start 1.500124 1.500124)
			(end -1.500124 1.500124)
			(stroke
				(width 0.1)
				(type default)
			)
			(layer "F.Fab")
		)
		(fp_line
			(start 1.500124 -1.500124)
			(end 1.500124 1.500124)
			(stroke
				(width 0.1)
				(type default)
			)
			(layer "F.Fab")
		)
		(fp_line
			(start -1.500124 1.500124)
			(end -1.500124 -1.500124)
			(stroke
				(width 0.1)
				(type default)
			)
			(layer "F.Fab")
		)
		(fp_line
			(start -1.500124 -1.500124)
			(end 1.500124 -1.500124)
			(stroke
				(width 0.1)
				(type default)
			)
			(layer "F.Fab")
		)
		(fp_poly
			(pts
				(xy -2.847848 -1.258062) (xy -2.847848 -0.242062) (xy -1.831848 -0.750062)
			)
			(stroke
				(width 0)
				(type default)
			)
			(fill yes)
			(layer "F.Fab")
		)
		(pad "1" smd rect
			(at -1.400048 -0.750062 90)
			(size 0.2286 0.6096)
			(layers "F.Cu" "F.Mask" "F.Paste")
			(net "SSD12_ADC_A1")
		)
		(pad "2" smd rect
			(at -1.400048 -0.249936 90)
			(size 0.2286 0.6096)
			(layers "F.Cu" "F.Mask" "F.Paste")
			(net "SSD12_ADC_A0")
		)
		(pad "3" smd rect
			(at -1.400048 0.249936 90)
			(size 0.2286 0.6096)
			(layers "F.Cu" "F.Mask" "F.Paste")
			(net "SSD12_ADC_ALERT_N")
		)
		(pad "4" smd rect
			(at -1.400048 0.750062 90)
			(size 0.2286 0.6096)
			(layers "F.Cu" "F.Mask" "F.Paste")
			(net "SMB_SSD12_ADC_SDA")
		)
		(pad "5" smd rect
			(at -0.750062 1.400048 180)
			(size 0.2286 0.6096)
			(layers "F.Cu" "F.Mask" "F.Paste")
			(net "SMB_SSD12_ADC_SCL")
		)
		(pad "6" smd rect
			(at -0.249936 1.400048 180)
			(size 0.2286 0.6096)
			(layers "F.Cu" "F.Mask" "F.Paste")
			(net "Net_8690")
		)
		(pad "7" smd rect
			(at 0.249936 1.400048 180)
			(size 0.2286 0.6096)
			(layers "F.Cu" "F.Mask" "F.Paste")
			(net "Net_8689")
		)
		(pad "8" smd rect
			(at 0.750062 1.400048 180)
			(size 0.2286 0.6096)
			(layers "F.Cu" "F.Mask" "F.Paste")
			(net "Net_8688")
		)
		(pad "9" smd rect
			(at 1.400048 0.750062 90)
			(size 0.2286 0.6096)
			(layers "F.Cu" "F.Mask" "F.Paste")
			(net "P3V3_AUX")
		)
		(pad "10" smd rect
			(at 1.400048 0.249936 90)
			(size 0.2286 0.6096)
			(layers "F.Cu" "F.Mask" "F.Paste")
			(net "GND")
		)
		(pad "11" smd rect
			(at 1.400048 -0.249936 90)
			(size 0.2286 0.6096)
			(layers "F.Cu" "F.Mask" "F.Paste")
			(net "P12V_SSD12_R")
		)
		(pad "12" smd rect
			(at 1.400048 -0.750062 90)
			(size 0.2286 0.6096)
			(layers "F.Cu" "F.Mask" "F.Paste")
			(net "P12V_SSD12_VIN_N")
		)
		(pad "13" smd rect
			(at 0.750062 -1.400048 180)
			(size 0.2286 0.6096)
			(layers "F.Cu" "F.Mask" "F.Paste")
			(net "P12V_SSD12_VIN_P")
		)
		(pad "14" smd rect
			(at 0.249936 -1.400048 180)
			(size 0.2286 0.6096)
			(layers "F.Cu" "F.Mask" "F.Paste")
			(net "Net_8687")
		)
		(pad "15" smd rect
			(at -0.249936 -1.400048 180)
			(size 0.2286 0.6096)
			(layers "F.Cu" "F.Mask" "F.Paste")
			(net "Net_8686")
		)
		(pad "16" smd rect
			(at -0.750062 -1.400048 180)
			(size 0.2286 0.6096)
			(layers "F.Cu" "F.Mask" "F.Paste")
			(net "Net_8685")
		)
		(pad "TH" smd rect
			(at 0 0 180)
			(size 1.7018 1.7018)
			(layers "F.Cu" "F.Mask" "F.Paste")
			(net "GND")
		)
		(zone
			(layer "F.Cu")
			(hatch none 0.5)
			(connect_pads
				(clearance 0)
			)
			(min_thickness 0.25)
			(keepout
				(tracks not_allowed)
				(vias allowed)
				(pads allowed)
				(copperpour not_allowed)
				(footprints allowed)
			)
			(placement
				(enabled no)
				(sheetname "")
			)
			(fill
				(thermal_gap 0.5)
				(thermal_bridge_width 0.5)
				(island_removal_mode 0)
			)
			(polygon
				(pts
					(xy 372.190518 -46.4185) (xy 372.190518 -45.399452) (xy 370.101622 -45.399452) (xy 370.101622 -47.488348)
					(xy 372.190518 -47.488348) (xy 372.190518 -46.4439) (xy 372.04777 -46.4439) (xy 372.04777 -47.3456)
					(xy 370.24437 -47.3456) (xy 370.24437 -45.5422) (xy 372.04777 -45.5422) (xy 372.04777 -46.4185)
				)
			)
		)
	)
	(footprint ""
		(layer "F.Cu")
		(at 224.856294 -182.51678 180)
		(property "Reference" "R5491"
			(at 0 0 180)
			(layer "F.SilkS")
			(hide yes)
			(effects
				(font
					(size 1.27 1.27)
				)
			)
		)
		(property "Value" ""
			(at 0 0 180)
			(layer "F.Fab")
			(effects
				(font
					(size 1.27 1.27)
				)
			)
		)
		(duplicate_pad_numbers_are_jumpers no)
		(fp_line
			(start 0.7874 0.4064)
			(end -0.7874 0.4064)
			(stroke
				(width 0.1524)
				(type default)
			)
			(layer "F.SilkS")
		)
		(fp_line
			(start 0.7874 -0.4064)
			(end 0.7874 0.4064)
			(stroke
				(width 0.1524)
				(type default)
			)
			(layer "F.SilkS")
		)
		(fp_line
			(start -0.7874 0.4064)
			(end -0.7874 -0.4064)
			(stroke
				(width 0.1524)
				(type default)
			)
			(layer "F.SilkS")
		)
		(fp_line
			(start -0.7874 -0.4064)
			(end 0.7874 -0.4064)
			(stroke
				(width 0.1524)
				(type default)
			)
			(layer "F.SilkS")
		)
		(fp_line
			(start 0.67945 0.3048)
			(end 0.120396 0.3048)
			(stroke
				(width 0.1)
				(type default)
			)
			(layer "F.Fab")
		)
		(fp_line
			(start 0.67945 -0.3048)
			(end 0.67945 0.3048)
			(stroke
				(width 0.1)
				(type default)
			)
			(layer "F.Fab")
		)
		(fp_line
			(start 0.12065 -0.2794)
			(end 0.12065 -0.3048)
			(stroke
				(width 0.1)
				(type default)
			)
			(layer "F.Fab")
		)
		(fp_line
			(start 0.12065 -0.3048)
			(end 0.67945 -0.3048)
			(stroke
				(width 0.1)
				(type default)
			)
			(layer "F.Fab")
		)
		(fp_line
			(start 0.120396 0.3048)
			(end 0.120396 0.2794)
			(stroke
				(width 0.1)
				(type default)
			)
			(layer "F.Fab")
		)
		(fp_line
			(start 0.120396 0.2794)
			(end -0.12065 0.2794)
			(stroke
				(width 0.1)
				(type default)
			)
			(layer "F.Fab")
		)
		(fp_line
			(start -0.12065 0.3048)
			(end -0.67945 0.3048)
			(stroke
				(width 0.1)
				(type default)
			)
			(layer "F.Fab")
		)
		(fp_line
			(start -0.12065 0.2794)
			(end -0.12065 0.3048)
			(stroke
				(width 0.1)
				(type default)
			)
			(layer "F.Fab")
		)
		(fp_line
			(start -0.12065 -0.2794)
			(end 0.12065 -0.2794)
			(stroke
				(width 0.1)
				(type default)
			)
			(layer "F.Fab")
		)
		(fp_line
			(start -0.12065 -0.305054)
			(end -0.12065 -0.2794)
			(stroke
				(width 0.1)
				(type default)
			)
			(layer "F.Fab")
		)
		(fp_line
			(start -0.67945 0.3048)
			(end -0.67945 -0.305054)
			(stroke
				(width 0.1)
				(type default)
			)
			(layer "F.Fab")
		)
		(fp_line
			(start -0.67945 -0.305054)
			(end -0.12065 -0.305054)
			(stroke
				(width 0.1)
				(type default)
			)
			(layer "F.Fab")
		)
		(pad "1" smd circle
			(at -0.40005 0 180)
			(size 0 0)
			(layers "F.Cu" "F.Mask" "F.Paste")
			(net "P3V3_AUX")
		)
		(pad "2" smd circle
			(at 0.40005 0 180)
			(size 0 0)
			(layers "F.Cu" "F.Mask" "F.Paste")
			(net "RST_BIC_BUF_RSMRST_N_BUF")
		)
	)
	(footprint ""
		(layer "F.Cu")
		(at 336.042 -174.117)
		(property "Reference" "R4738"
			(at 0 0 0)
			(layer "F.SilkS")
			(hide yes)
			(effects
				(font
					(size 1.27 1.27)
				)
			)
		)
		(property "Value" ""
			(at 0 0 0)
			(layer "F.Fab")
			(effects
				(font
					(size 1.27 1.27)
				)
			)
		)
		(duplicate_pad_numbers_are_jumpers no)
		(fp_line
			(start -0.7874 -0.4064)
			(end 0.7874 -0.4064)
			(stroke
				(width 0.1524)
				(type default)
			)
			(layer "F.SilkS")
		)
		(fp_line
			(start -0.7874 0.4064)
			(end -0.7874 -0.4064)
			(stroke
				(width 0.1524)
				(type default)
			)
			(layer "F.SilkS")
		)
		(fp_line
			(start 0.7874 -0.4064)
			(end 0.7874 0.4064)
			(stroke
				(width 0.1524)
				(type default)
			)
			(layer "F.SilkS")
		)
		(fp_line
			(start 0.7874 0.4064)
			(end -0.7874 0.4064)
			(stroke
				(width 0.1524)
				(type default)
			)
			(layer "F.SilkS")
		)
		(fp_line
			(start -0.67945 -0.305054)
			(end -0.12065 -0.305054)
			(stroke
				(width 0.1)
				(type default)
			)
			(layer "F.Fab")
		)
		(fp_line
			(start -0.67945 0.3048)
			(end -0.67945 -0.305054)
			(stroke
				(width 0.1)
				(type default)
			)
			(layer "F.Fab")
		)
		(fp_line
			(start -0.12065 -0.305054)
			(end -0.12065 -0.2794)
			(stroke
				(width 0.1)
				(type default)
			)
			(layer "F.Fab")
		)
		(fp_line
			(start -0.12065 -0.2794)
			(end 0.12065 -0.2794)
			(stroke
				(width 0.1)
				(type default)
			)
			(layer "F.Fab")
		)
		(fp_line
			(start -0.12065 0.2794)
			(end -0.12065 0.3048)
			(stroke
				(width 0.1)
				(type default)
			)
			(layer "F.Fab")
		)
		(fp_line
			(start -0.12065 0.3048)
			(end -0.67945 0.3048)
			(stroke
				(width 0.1)
				(type default)
			)
			(layer "F.Fab")
		)
		(fp_line
			(start 0.120396 0.2794)
			(end -0.12065 0.2794)
			(stroke
				(width 0.1)
				(type default)
			)
			(layer "F.Fab")
		)
		(fp_line
			(start 0.120396 0.3048)
			(end 0.120396 0.2794)
			(stroke
				(width 0.1)
				(type default)
			)
			(layer "F.Fab")
		)
		(fp_line
			(start 0.12065 -0.3048)
			(end 0.67945 -0.3048)
			(stroke
				(width 0.1)
				(type default)
			)
			(layer "F.Fab")
		)
		(fp_line
			(start 0.12065 -0.2794)
			(end 0.12065 -0.3048)
			(stroke
				(width 0.1)
				(type default)
			)
			(layer "F.Fab")
		)
		(fp_line
			(start 0.67945 -0.3048)
			(end 0.67945 0.3048)
			(stroke
				(width 0.1)
				(type default)
			)
			(layer "F.Fab")
		)
		(fp_line
			(start 0.67945 0.3048)
			(end 0.120396 0.3048)
			(stroke
				(width 0.1)
				(type default)
			)
			(layer "F.Fab")
		)
		(pad "1" smd circle
			(at -0.40005 0)
			(size 0 0)
			(layers "F.Cu" "F.Mask" "F.Paste")
			(net "PEX2_PCA9555_INT_N")
		)
		(pad "2" smd circle
			(at 0.40005 0)
			(size 0 0)
			(layers "F.Cu" "F.Mask" "F.Paste")
			(net "PEX2_PCA9555_1_INT_N")
		)
	)
	(footprint ""
		(layer "F.Cu")
		(at 104.851454 -99.177602 -90)
		(property "Reference" "PD12"
			(at 4.334002 -2.693416 90)
			(unlocked yes)
			(layer "F.SilkS")
			(effects
				(font
					(size 0.7874 0.5842)
					(thickness 0.1524)
				)
				(justify left)
			)
		)
		(property "Value" ""
			(at 0 0 270)
			(layer "F.Fab")
			(effects
				(font
					(size 1.27 1.27)
				)
			)
		)
		(duplicate_pad_numbers_are_jumpers no)
		(fp_line
			(start -3.656584 1.970024)
			(end 4.240784 1.970024)
			(stroke
				(width 0.1524)
				(type default)
			)
			(layer "F.SilkS")
		)
		(fp_line
			(start 4.240784 1.970024)
			(end 4.240784 -1.970024)
			(stroke
				(width 0.1524)
				(type default)
			)
			(layer "F.SilkS")
		)
		(fp_line
			(start -3.656584 -1.970024)
			(end -3.656584 1.970024)
			(stroke
				(width 0.1524)
				(type default)
			)
			(layer "F.SilkS")
		)
		(fp_line
			(start 4.240784 -1.970024)
			(end -3.656584 -1.970024)
			(stroke
				(width 0.1524)
				(type default)
			)
			(layer "F.SilkS")
		)
		(fp_rect
			(start 4.240784 1.970024)
			(end 3.580384 -1.970024)
			(stroke
				(width 0)
				(type default)
			)
			(fill yes)
			(layer "F.SilkS")
		)
		(fp_line
			(start -2.3749 1.970024)
			(end 2.3749 1.970024)
			(stroke
				(width 0.1)
				(type default)
			)
			(layer "F.Fab")
		)
		(fp_line
			(start 2.3749 1.970024)
			(end 2.3749 -1.970024)
			(stroke
				(width 0.1)
				(type default)
			)
			(layer "F.Fab")
		)
		(fp_line
			(start -2.3749 -1.970024)
			(end -2.3749 1.970024)
			(stroke
				(width 0.1)
				(type default)
			)
			(layer "F.Fab")
		)
		(fp_line
			(start 2.3749 -1.970024)
			(end -2.3749 -1.970024)
			(stroke
				(width 0.1)
				(type default)
			)
			(layer "F.Fab")
		)
		(fp_text user "+"
			(at -4.9784 -0.23495 270)
			(unlocked yes)
			(layer "F.Fab")
			(effects
				(font
					(size 1.905 1.4224)
					(thickness 0.1524)
				)
				(justify left)
			)
		)
		(fp_text user "-"
			(at 4.1656 -0.23495 270)
			(unlocked yes)
			(layer "F.Fab")
			(effects
				(font
					(size 1.905 1.4224)
					(thickness 0.1524)
				)
				(justify left)
			)
		)
		(pad "A" smd rect
			(at -2.450084 0 270)
			(size 2.159 2.2606)
			(layers "F.Cu" "F.Mask" "F.Paste")
			(net "GND")
		)
		(pad "C" smd rect
			(at 2.450084 0 270)
			(size 2.159 2.2606)
			(layers "F.Cu" "F.Mask" "F.Paste")
			(net "P12V_AUX")
		)
	)
)
